FILE_TYPE = CONNECTIVITY;
{Allegro Design Entry HDL 16.6-p007 (v16-6-112F) 10/10/2012}
"PAGE_NUMBER" = 11;
0"NC";
END.
